(kicad_pcb
	(version 20260206)
	(generator "pcbnew")
	(generator_version "10.0")
	(general
		(thickness 1.6)
		(legacy_teardrops no)
	)
	(paper "A4")
	(title_block
		(title "04192023_DAF0TMB3IC0_F0TG_MB_C_brd_V02_OCP.brd")
		(comment 1 "Grand Teton / footprints 8150-8155 of 8354")
	)
	(layers
		(0 "F.Cu" signal "TOP")
		(4 "In1.Cu" signal "GND")
		(6 "In2.Cu" signal "IN1")
		(8 "In3.Cu" signal "GND1")
		(10 "In4.Cu" signal "IN2")
		(12 "In5.Cu" signal "GND2")
		(14 "In6.Cu" signal "IN3")
		(16 "In7.Cu" signal "GND3")
		(18 "In8.Cu" signal "VCC")
		(20 "In9.Cu" signal "VCC1")
		(22 "In10.Cu" signal "GND4")
		(24 "In11.Cu" signal "IN4")
		(26 "In12.Cu" signal "GND5")
		(28 "In13.Cu" signal "IN5")
		(30 "In14.Cu" signal "GND6")
		(32 "In15.Cu" signal "IN6")
		(34 "In16.Cu" signal "GND7")
		(2 "B.Cu" signal "BOTTOM")
		(9 "F.Adhes" user "F.Adhesive")
		(11 "B.Adhes" user "B.Adhesive")
		(13 "F.Paste" user "Package Geometry/Pastemask Top")
		(15 "B.Paste" user "Package Geometry/Pastemask Bottom")
		(5 "F.SilkS" user "Ref Des/Silkscreen Top")
		(7 "B.SilkS" user "Ref Des/Silkscreen Bottom")
		(1 "F.Mask" user "Board Geometry/Soldermask Top")
		(3 "B.Mask" user "Board Geometry/Soldermask Bottom")
		(17 "Dwgs.User" user "User.Drawings")
		(19 "Cmts.User" user "User.Comments")
		(21 "Eco1.User" user "User.Eco1")
		(23 "Eco2.User" user "User.Eco2")
		(25 "Edge.Cuts" user "Board Geometry/Outline")
		(27 "Margin" user)
		(31 "F.CrtYd" user "Package Geometry/Place Bound Top")
		(29 "B.CrtYd" user "Package Geometry/Place Bound Bottom")
		(35 "F.Fab" user "Ref Des/Assembly Top")
		(33 "B.Fab" user "Ref Des/Assembly Bottom")
	)
	(footprint ""
		(layer "B.Cu")
		(at 363.550454 -253.43231)
		(property "Reference" "C2532"
			(at 0 0 0)
			(layer "B.SilkS")
			(hide yes)
			(effects
				(font
					(size 1.27 1.27)
				)
				(justify mirror)
			)
		)
		(property "Value" ""
			(at 0 0 0)
			(layer "B.Fab")
			(effects
				(font
					(size 1.27 1.27)
				)
				(justify mirror)
			)
		)
		(duplicate_pad_numbers_are_jumpers no)
		(fp_line
			(start -0.7874 -0.4064)
			(end -0.7874 0.4064)
			(stroke
				(width 0.1524)
				(type default)
			)
			(layer "B.SilkS")
		)
		(fp_line
			(start -0.7874 0.4064)
			(end 0.7874 0.4064)
			(stroke
				(width 0.1524)
				(type default)
			)
			(layer "B.SilkS")
		)
		(fp_line
			(start 0.7874 -0.4064)
			(end -0.7874 -0.4064)
			(stroke
				(width 0.1524)
				(type default)
			)
			(layer "B.SilkS")
		)
		(fp_line
			(start 0.7874 0.4064)
			(end 0.7874 -0.4064)
			(stroke
				(width 0.1524)
				(type default)
			)
			(layer "B.SilkS")
		)
		(fp_line
			(start -0.67945 -0.3048)
			(end -0.67945 0.3048)
			(stroke
				(width 0.1)
				(type default)
			)
			(layer "B.Fab")
		)
		(fp_line
			(start -0.67945 0.3048)
			(end -0.120396 0.3048)
			(stroke
				(width 0.1)
				(type default)
			)
			(layer "B.Fab")
		)
		(fp_line
			(start -0.12065 -0.3048)
			(end -0.67945 -0.3048)
			(stroke
				(width 0.1)
				(type default)
			)
			(layer "B.Fab")
		)
		(fp_line
			(start -0.12065 -0.2794)
			(end -0.12065 -0.3048)
			(stroke
				(width 0.1)
				(type default)
			)
			(layer "B.Fab")
		)
		(fp_line
			(start -0.120396 0.2794)
			(end 0.12065 0.2794)
			(stroke
				(width 0.1)
				(type default)
			)
			(layer "B.Fab")
		)
		(fp_line
			(start -0.120396 0.3048)
			(end -0.120396 0.2794)
			(stroke
				(width 0.1)
				(type default)
			)
			(layer "B.Fab")
		)
		(fp_line
			(start 0.12065 -0.305054)
			(end 0.12065 -0.2794)
			(stroke
				(width 0.1)
				(type default)
			)
			(layer "B.Fab")
		)
		(fp_line
			(start 0.12065 -0.2794)
			(end -0.12065 -0.2794)
			(stroke
				(width 0.1)
				(type default)
			)
			(layer "B.Fab")
		)
		(fp_line
			(start 0.12065 0.2794)
			(end 0.12065 0.3048)
			(stroke
				(width 0.1)
				(type default)
			)
			(layer "B.Fab")
		)
		(fp_line
			(start 0.12065 0.3048)
			(end 0.67945 0.3048)
			(stroke
				(width 0.1)
				(type default)
			)
			(layer "B.Fab")
		)
		(fp_line
			(start 0.67945 -0.305054)
			(end 0.12065 -0.305054)
			(stroke
				(width 0.1)
				(type default)
			)
			(layer "B.Fab")
		)
		(fp_line
			(start 0.67945 0.3048)
			(end 0.67945 -0.305054)
			(stroke
				(width 0.1)
				(type default)
			)
			(layer "B.Fab")
		)
		(pad "1" smd circle
			(at 0.40005 0 180)
			(size 0 0)
			(layers "B.Cu" "B.Mask" "B.Paste")
			(net "PVDDCR_SOC_P0")
		)
		(pad "2" smd circle
			(at -0.40005 0 180)
			(size 0 0)
			(layers "B.Cu" "B.Mask" "B.Paste")
			(net "GND")
		)
	)
	(footprint ""
		(layer "B.Cu")
		(at 164.062918 -121.701814 180)
		(property "Reference" "C1209"
			(at 0 0 0)
			(layer "B.SilkS")
			(hide yes)
			(effects
				(font
					(size 1.27 1.27)
				)
				(justify mirror)
			)
		)
		(property "Value" ""
			(at 0 0 0)
			(layer "B.Fab")
			(effects
				(font
					(size 1.27 1.27)
				)
				(justify mirror)
			)
		)
		(duplicate_pad_numbers_are_jumpers no)
		(fp_line
			(start 0.7874 0.4064)
			(end 0.7874 -0.4064)
			(stroke
				(width 0.1524)
				(type default)
			)
			(layer "B.SilkS")
		)
		(fp_line
			(start 0.7874 -0.4064)
			(end -0.7874 -0.4064)
			(stroke
				(width 0.1524)
				(type default)
			)
			(layer "B.SilkS")
		)
		(fp_line
			(start -0.7874 0.4064)
			(end 0.7874 0.4064)
			(stroke
				(width 0.1524)
				(type default)
			)
			(layer "B.SilkS")
		)
		(fp_line
			(start -0.7874 -0.4064)
			(end -0.7874 0.4064)
			(stroke
				(width 0.1524)
				(type default)
			)
			(layer "B.SilkS")
		)
		(fp_line
			(start 0.67945 0.3048)
			(end 0.67945 -0.305054)
			(stroke
				(width 0.1)
				(type default)
			)
			(layer "B.Fab")
		)
		(fp_line
			(start 0.67945 -0.305054)
			(end 0.12065 -0.305054)
			(stroke
				(width 0.1)
				(type default)
			)
			(layer "B.Fab")
		)
		(fp_line
			(start 0.12065 0.3048)
			(end 0.67945 0.3048)
			(stroke
				(width 0.1)
				(type default)
			)
			(layer "B.Fab")
		)
		(fp_line
			(start 0.12065 0.2794)
			(end 0.12065 0.3048)
			(stroke
				(width 0.1)
				(type default)
			)
			(layer "B.Fab")
		)
		(fp_line
			(start 0.12065 -0.2794)
			(end -0.12065 -0.2794)
			(stroke
				(width 0.1)
				(type default)
			)
			(layer "B.Fab")
		)
		(fp_line
			(start 0.12065 -0.305054)
			(end 0.12065 -0.2794)
			(stroke
				(width 0.1)
				(type default)
			)
			(layer "B.Fab")
		)
		(fp_line
			(start -0.120396 0.3048)
			(end -0.120396 0.2794)
			(stroke
				(width 0.1)
				(type default)
			)
			(layer "B.Fab")
		)
		(fp_line
			(start -0.120396 0.2794)
			(end 0.12065 0.2794)
			(stroke
				(width 0.1)
				(type default)
			)
			(layer "B.Fab")
		)
		(fp_line
			(start -0.12065 -0.2794)
			(end -0.12065 -0.3048)
			(stroke
				(width 0.1)
				(type default)
			)
			(layer "B.Fab")
		)
		(fp_line
			(start -0.12065 -0.3048)
			(end -0.67945 -0.3048)
			(stroke
				(width 0.1)
				(type default)
			)
			(layer "B.Fab")
		)
		(fp_line
			(start -0.67945 0.3048)
			(end -0.120396 0.3048)
			(stroke
				(width 0.1)
				(type default)
			)
			(layer "B.Fab")
		)
		(fp_line
			(start -0.67945 -0.3048)
			(end -0.67945 0.3048)
			(stroke
				(width 0.1)
				(type default)
			)
			(layer "B.Fab")
		)
		(pad "1" smd circle
			(at 0.40005 0)
			(size 0 0)
			(layers "B.Cu" "B.Mask" "B.Paste")
			(net "SCM_SYS_PWROK_R2")
		)
		(pad "2" smd circle
			(at -0.40005 0)
			(size 0 0)
			(layers "B.Cu" "B.Mask" "B.Paste")
			(net "GND")
		)
	)
	(footprint ""
		(layer "B.Cu")
		(at 88.138 -147.955 180)
		(property "Reference" "PR8009"
			(at 0 0 0)
			(layer "B.SilkS")
			(hide yes)
			(effects
				(font
					(size 1.27 1.27)
				)
				(justify mirror)
			)
		)
		(property "Value" ""
			(at 0 0 0)
			(layer "B.Fab")
			(effects
				(font
					(size 1.27 1.27)
				)
				(justify mirror)
			)
		)
		(duplicate_pad_numbers_are_jumpers no)
		(fp_line
			(start 0.7874 0.4064)
			(end 0.7874 -0.4064)
			(stroke
				(width 0.1524)
				(type default)
			)
			(layer "B.SilkS")
		)
		(fp_line
			(start 0.7874 -0.4064)
			(end -0.7874 -0.4064)
			(stroke
				(width 0.1524)
				(type default)
			)
			(layer "B.SilkS")
		)
		(fp_line
			(start -0.7874 0.4064)
			(end 0.7874 0.4064)
			(stroke
				(width 0.1524)
				(type default)
			)
			(layer "B.SilkS")
		)
		(fp_line
			(start -0.7874 -0.4064)
			(end -0.7874 0.4064)
			(stroke
				(width 0.1524)
				(type default)
			)
			(layer "B.SilkS")
		)
		(fp_line
			(start 0.67945 0.3048)
			(end 0.67945 -0.305054)
			(stroke
				(width 0.1)
				(type default)
			)
			(layer "B.Fab")
		)
		(fp_line
			(start 0.67945 -0.305054)
			(end 0.12065 -0.305054)
			(stroke
				(width 0.1)
				(type default)
			)
			(layer "B.Fab")
		)
		(fp_line
			(start 0.12065 0.3048)
			(end 0.67945 0.3048)
			(stroke
				(width 0.1)
				(type default)
			)
			(layer "B.Fab")
		)
		(fp_line
			(start 0.12065 0.2794)
			(end 0.12065 0.3048)
			(stroke
				(width 0.1)
				(type default)
			)
			(layer "B.Fab")
		)
		(fp_line
			(start 0.12065 -0.2794)
			(end -0.12065 -0.2794)
			(stroke
				(width 0.1)
				(type default)
			)
			(layer "B.Fab")
		)
		(fp_line
			(start 0.12065 -0.305054)
			(end 0.12065 -0.2794)
			(stroke
				(width 0.1)
				(type default)
			)
			(layer "B.Fab")
		)
		(fp_line
			(start -0.120396 0.3048)
			(end -0.120396 0.2794)
			(stroke
				(width 0.1)
				(type default)
			)
			(layer "B.Fab")
		)
		(fp_line
			(start -0.120396 0.2794)
			(end 0.12065 0.2794)
			(stroke
				(width 0.1)
				(type default)
			)
			(layer "B.Fab")
		)
		(fp_line
			(start -0.12065 -0.2794)
			(end -0.12065 -0.3048)
			(stroke
				(width 0.1)
				(type default)
			)
			(layer "B.Fab")
		)
		(fp_line
			(start -0.12065 -0.3048)
			(end -0.67945 -0.3048)
			(stroke
				(width 0.1)
				(type default)
			)
			(layer "B.Fab")
		)
		(fp_line
			(start -0.67945 0.3048)
			(end -0.120396 0.3048)
			(stroke
				(width 0.1)
				(type default)
			)
			(layer "B.Fab")
		)
		(fp_line
			(start -0.67945 -0.3048)
			(end -0.67945 0.3048)
			(stroke
				(width 0.1)
				(type default)
			)
			(layer "B.Fab")
		)
		(pad "1" smd circle
			(at 0.40005 0)
			(size 0 0)
			(layers "B.Cu" "B.Mask" "B.Paste")
			(net "SVID_PVDDCR_CPU0_P1_SVC_R")
		)
		(pad "2" smd circle
			(at -0.40005 0)
			(size 0 0)
			(layers "B.Cu" "B.Mask" "B.Paste")
			(net "SVID_PVDDCR_CPU0_P1_SVC_R1")
		)
	)
	(footprint ""
		(layer "B.Cu")
		(at 369.646454 -250.89231)
		(property "Reference" "C2557"
			(at 0 0 0)
			(layer "B.SilkS")
			(hide yes)
			(effects
				(font
					(size 1.27 1.27)
				)
				(justify mirror)
			)
		)
		(property "Value" ""
			(at 0 0 0)
			(layer "B.Fab")
			(effects
				(font
					(size 1.27 1.27)
				)
				(justify mirror)
			)
		)
		(duplicate_pad_numbers_are_jumpers no)
		(fp_line
			(start -0.7874 -0.4064)
			(end -0.7874 0.4064)
			(stroke
				(width 0.1524)
				(type default)
			)
			(layer "B.SilkS")
		)
		(fp_line
			(start -0.7874 0.4064)
			(end 0.7874 0.4064)
			(stroke
				(width 0.1524)
				(type default)
			)
			(layer "B.SilkS")
		)
		(fp_line
			(start 0.7874 -0.4064)
			(end -0.7874 -0.4064)
			(stroke
				(width 0.1524)
				(type default)
			)
			(layer "B.SilkS")
		)
		(fp_line
			(start 0.7874 0.4064)
			(end 0.7874 -0.4064)
			(stroke
				(width 0.1524)
				(type default)
			)
			(layer "B.SilkS")
		)
		(fp_line
			(start -0.67945 -0.3048)
			(end -0.67945 0.3048)
			(stroke
				(width 0.1)
				(type default)
			)
			(layer "B.Fab")
		)
		(fp_line
			(start -0.67945 0.3048)
			(end -0.120396 0.3048)
			(stroke
				(width 0.1)
				(type default)
			)
			(layer "B.Fab")
		)
		(fp_line
			(start -0.12065 -0.3048)
			(end -0.67945 -0.3048)
			(stroke
				(width 0.1)
				(type default)
			)
			(layer "B.Fab")
		)
		(fp_line
			(start -0.12065 -0.2794)
			(end -0.12065 -0.3048)
			(stroke
				(width 0.1)
				(type default)
			)
			(layer "B.Fab")
		)
		(fp_line
			(start -0.120396 0.2794)
			(end 0.12065 0.2794)
			(stroke
				(width 0.1)
				(type default)
			)
			(layer "B.Fab")
		)
		(fp_line
			(start -0.120396 0.3048)
			(end -0.120396 0.2794)
			(stroke
				(width 0.1)
				(type default)
			)
			(layer "B.Fab")
		)
		(fp_line
			(start 0.12065 -0.305054)
			(end 0.12065 -0.2794)
			(stroke
				(width 0.1)
				(type default)
			)
			(layer "B.Fab")
		)
		(fp_line
			(start 0.12065 -0.2794)
			(end -0.12065 -0.2794)
			(stroke
				(width 0.1)
				(type default)
			)
			(layer "B.Fab")
		)
		(fp_line
			(start 0.12065 0.2794)
			(end 0.12065 0.3048)
			(stroke
				(width 0.1)
				(type default)
			)
			(layer "B.Fab")
		)
		(fp_line
			(start 0.12065 0.3048)
			(end 0.67945 0.3048)
			(stroke
				(width 0.1)
				(type default)
			)
			(layer "B.Fab")
		)
		(fp_line
			(start 0.67945 -0.305054)
			(end 0.12065 -0.305054)
			(stroke
				(width 0.1)
				(type default)
			)
			(layer "B.Fab")
		)
		(fp_line
			(start 0.67945 0.3048)
			(end 0.67945 -0.305054)
			(stroke
				(width 0.1)
				(type default)
			)
			(layer "B.Fab")
		)
		(pad "1" smd circle
			(at 0.40005 0 180)
			(size 0 0)
			(layers "B.Cu" "B.Mask" "B.Paste")
			(net "PVDDCR_SOC_P0")
		)
		(pad "2" smd circle
			(at -0.40005 0 180)
			(size 0 0)
			(layers "B.Cu" "B.Mask" "B.Paste")
			(net "GND")
		)
	)
	(footprint ""
		(layer "B.Cu")
		(at 421.01897 -398.942052 90)
		(property "Reference" "C986"
			(at 0 0 90)
			(layer "B.SilkS")
			(hide yes)
			(effects
				(font
					(size 1.27 1.27)
				)
				(justify mirror)
			)
		)
		(property "Value" ""
			(at 0 0 90)
			(layer "B.Fab")
			(effects
				(font
					(size 1.27 1.27)
				)
				(justify mirror)
			)
		)
		(duplicate_pad_numbers_are_jumpers no)
		(fp_line
			(start 0.7874 -0.4064)
			(end -0.7874 -0.4064)
			(stroke
				(width 0.1524)
				(type default)
			)
			(layer "B.SilkS")
		)
		(fp_line
			(start -0.7874 -0.4064)
			(end -0.7874 0.4064)
			(stroke
				(width 0.1524)
				(type default)
			)
			(layer "B.SilkS")
		)
		(fp_line
			(start 0.7874 0.4064)
			(end 0.7874 -0.4064)
			(stroke
				(width 0.1524)
				(type default)
			)
			(layer "B.SilkS")
		)
		(fp_line
			(start -0.7874 0.4064)
			(end 0.7874 0.4064)
			(stroke
				(width 0.1524)
				(type default)
			)
			(layer "B.SilkS")
		)
		(fp_line
			(start 0.67945 -0.305054)
			(end 0.12065 -0.305054)
			(stroke
				(width 0.1)
				(type default)
			)
			(layer "B.Fab")
		)
		(fp_line
			(start 0.12065 -0.305054)
			(end 0.12065 -0.2794)
			(stroke
				(width 0.1)
				(type default)
			)
			(layer "B.Fab")
		)
		(fp_line
			(start -0.12065 -0.3048)
			(end -0.67945 -0.3048)
			(stroke
				(width 0.1)
				(type default)
			)
			(layer "B.Fab")
		)
		(fp_line
			(start -0.67945 -0.3048)
			(end -0.67945 0.3048)
			(stroke
				(width 0.1)
				(type default)
			)
			(layer "B.Fab")
		)
		(fp_line
			(start 0.12065 -0.2794)
			(end -0.12065 -0.2794)
			(stroke
				(width 0.1)
				(type default)
			)
			(layer "B.Fab")
		)
		(fp_line
			(start -0.12065 -0.2794)
			(end -0.12065 -0.3048)
			(stroke
				(width 0.1)
				(type default)
			)
			(layer "B.Fab")
		)
		(fp_line
			(start 0.12065 0.2794)
			(end 0.12065 0.3048)
			(stroke
				(width 0.1)
				(type default)
			)
			(layer "B.Fab")
		)
		(fp_line
			(start -0.120396 0.2794)
			(end 0.12065 0.2794)
			(stroke
				(width 0.1)
				(type default)
			)
			(layer "B.Fab")
		)
		(fp_line
			(start 0.67945 0.3048)
			(end 0.67945 -0.305054)
			(stroke
				(width 0.1)
				(type default)
			)
			(layer "B.Fab")
		)
		(fp_line
			(start 0.12065 0.3048)
			(end 0.67945 0.3048)
			(stroke
				(width 0.1)
				(type default)
			)
			(layer "B.Fab")
		)
		(fp_line
			(start -0.120396 0.3048)
			(end -0.120396 0.2794)
			(stroke
				(width 0.1)
				(type default)
			)
			(layer "B.Fab")
		)
		(fp_line
			(start -0.67945 0.3048)
			(end -0.120396 0.3048)
			(stroke
				(width 0.1)
				(type default)
			)
			(layer "B.Fab")
		)
		(pad "1" smd circle
			(at 0.40005 0 270)
			(size 0 0)
			(layers "B.Cu" "B.Mask" "B.Paste")
			(net "P0V9_CPU0_RT2_2A")
		)
		(pad "2" smd circle
			(at -0.40005 0 270)
			(size 0 0)
			(layers "B.Cu" "B.Mask" "B.Paste")
			(net "GND")
		)
	)
	(footprint ""
		(layer "B.Cu")
		(at 183.551068 -111.863124 -90)
		(property "Reference" "C1126"
			(at 0 0 90)
			(layer "B.SilkS")
			(hide yes)
			(effects
				(font
					(size 1.27 1.27)
				)
				(justify mirror)
			)
		)
		(property "Value" ""
			(at 0 0 90)
			(layer "B.Fab")
			(effects
				(font
					(size 1.27 1.27)
				)
				(justify mirror)
			)
		)
		(duplicate_pad_numbers_are_jumpers no)
		(fp_line
			(start -0.69215 0.2921)
			(end 0.69215 0.2921)
			(stroke
				(width 0.1524)
				(type default)
			)
			(layer "B.SilkS")
		)
		(fp_line
			(start 0.69215 0.2921)
			(end 0.69215 -0.2921)
			(stroke
				(width 0.1524)
				(type default)
			)
			(layer "B.SilkS")
		)
		(fp_line
			(start -0.69215 -0.2921)
			(end -0.69215 0.2921)
			(stroke
				(width 0.1524)
				(type default)
			)
			(layer "B.SilkS")
		)
		(fp_line
			(start 0.69215 -0.2921)
			(end -0.69215 -0.2921)
			(stroke
				(width 0.1524)
				(type default)
			)
			(layer "B.SilkS")
		)
		(fp_line
			(start -0.51435 0.2794)
			(end 0.51435 0.2794)
			(stroke
				(width 0.1)
				(type default)
			)
			(layer "B.Fab")
		)
		(fp_line
			(start 0.51435 0.2794)
			(end 0.51435 -0.2794)
			(stroke
				(width 0.1)
				(type default)
			)
			(layer "B.Fab")
		)
		(fp_line
			(start -0.51435 -0.2794)
			(end -0.51435 0.2794)
			(stroke
				(width 0.1)
				(type default)
			)
			(layer "B.Fab")
		)
		(fp_line
			(start 0.51435 -0.2794)
			(end -0.51435 -0.2794)
			(stroke
				(width 0.1)
				(type default)
			)
			(layer "B.Fab")
		)
		(pad "1" smd circle
			(at 0.40005 0 90)
			(size 0 0)
			(layers "B.Cu" "B.Mask" "B.Paste")
			(net "P1V8_AUX")
		)
		(pad "2" smd circle
			(at -0.40005 0 90)
			(size 0 0)
			(layers "B.Cu" "B.Mask" "B.Paste")
			(net "GND")
		)
		(zone
			(layer "B.Cu")
			(hatch none 0.5)
			(connect_pads
				(clearance 0)
			)
			(min_thickness 0.25)
			(keepout
				(tracks not_allowed)
				(vias allowed)
				(pads allowed)
				(copperpour not_allowed)
				(footprints allowed)
			)
			(placement
				(enabled no)
				(sheetname "")
			)
			(fill
				(thermal_gap 0.5)
				(thermal_bridge_width 0.5)
				(island_removal_mode 0)
			)
			(polygon
				(pts
					(xy 183.405272 -111.764064) (xy 183.405272 -111.963454) (xy 183.463438 -112.053624) (xy 183.638698 -112.053624)
					(xy 183.697118 -111.963454) (xy 183.697118 -111.764064) (xy 183.638952 -111.672624) (xy 183.463438 -111.672624)
				)
			)
		)
	)
)
